(kicad_pcb
	(version 20260206)
	(generator "pcbnew")
	(generator_version "10.0")
	(general
		(thickness 1.6)
		(legacy_teardrops no)
	)
	(paper "A4")
	(title_block
		(title "04192023_DAF0TMB3IC0_F0TG_MB_C_brd_V02_OCP.brd")
		(comment 1 "Grand Teton / footprints 2606-2610 of 8354")
	)
	(layers
		(0 "F.Cu" signal "TOP")
		(4 "In1.Cu" signal "GND")
		(6 "In2.Cu" signal "IN1")
		(8 "In3.Cu" signal "GND1")
		(10 "In4.Cu" signal "IN2")
		(12 "In5.Cu" signal "GND2")
		(14 "In6.Cu" signal "IN3")
		(16 "In7.Cu" signal "GND3")
		(18 "In8.Cu" signal "VCC")
		(20 "In9.Cu" signal "VCC1")
		(22 "In10.Cu" signal "GND4")
		(24 "In11.Cu" signal "IN4")
		(26 "In12.Cu" signal "GND5")
		(28 "In13.Cu" signal "IN5")
		(30 "In14.Cu" signal "GND6")
		(32 "In15.Cu" signal "IN6")
		(34 "In16.Cu" signal "GND7")
		(2 "B.Cu" signal "BOTTOM")
		(9 "F.Adhes" user "F.Adhesive")
		(11 "B.Adhes" user "B.Adhesive")
		(13 "F.Paste" user "Package Geometry/Pastemask Top")
		(15 "B.Paste" user "Package Geometry/Pastemask Bottom")
		(5 "F.SilkS" user "Ref Des/Silkscreen Top")
		(7 "B.SilkS" user "Ref Des/Silkscreen Bottom")
		(1 "F.Mask" user "Board Geometry/Soldermask Top")
		(3 "B.Mask" user "Board Geometry/Soldermask Bottom")
		(17 "Dwgs.User" user "User.Drawings")
		(19 "Cmts.User" user "User.Comments")
		(21 "Eco1.User" user "User.Eco1")
		(23 "Eco2.User" user "User.Eco2")
		(25 "Edge.Cuts" user "Board Geometry/Outline")
		(27 "Margin" user)
		(31 "F.CrtYd" user "Package Geometry/Place Bound Top")
		(29 "B.CrtYd" user "Package Geometry/Place Bound Bottom")
		(35 "F.Fab" user "Ref Des/Assembly Top")
		(33 "B.Fab" user "Ref Des/Assembly Bottom")
	)
	(footprint ""
		(layer "F.Cu")
		(at 95.453454 -335.029302)
		(property "Reference" "PU38"
			(at -2.616454 -8.479028 0)
			(unlocked yes)
			(layer "F.SilkS")
			(effects
				(font
					(size 0.7874 0.5842)
					(thickness 0.1524)
				)
				(justify left)
			)
		)
		(property "Value" ""
			(at 0 0 0)
			(layer "F.Fab")
			(effects
				(font
					(size 1.27 1.27)
				)
			)
		)
		(duplicate_pad_numbers_are_jumpers no)
		(fp_line
			(start -2.500122 -2.999994)
			(end -2.24409 -2.999994)
			(stroke
				(width 0.1524)
				(type default)
			)
			(layer "F.SilkS")
		)
		(fp_line
			(start -2.500122 -2.529078)
			(end -2.500122 -2.999994)
			(stroke
				(width 0.1524)
				(type default)
			)
			(layer "F.SilkS")
		)
		(fp_line
			(start -2.500122 0.6604)
			(end -2.500122 0.229108)
			(stroke
				(width 0.1524)
				(type default)
			)
			(layer "F.SilkS")
		)
		(fp_line
			(start -2.500122 2.999994)
			(end -2.500122 2.339594)
			(stroke
				(width 0.1524)
				(type default)
			)
			(layer "F.SilkS")
		)
		(fp_line
			(start -2.2987 2.999994)
			(end -2.500122 2.999994)
			(stroke
				(width 0.1524)
				(type default)
			)
			(layer "F.SilkS")
		)
		(fp_line
			(start 2.31394 -2.999994)
			(end 2.500122 -2.999994)
			(stroke
				(width 0.1524)
				(type default)
			)
			(layer "F.SilkS")
		)
		(fp_line
			(start 2.500122 -2.999994)
			(end 2.500122 -2.44348)
			(stroke
				(width 0.1524)
				(type default)
			)
			(layer "F.SilkS")
		)
		(fp_line
			(start 2.500122 2.339594)
			(end 2.500122 2.999994)
			(stroke
				(width 0.1524)
				(type default)
			)
			(layer "F.SilkS")
		)
		(fp_line
			(start 2.500122 2.999994)
			(end 2.2987 2.999994)
			(stroke
				(width 0.1524)
				(type default)
			)
			(layer "F.SilkS")
		)
		(fp_poly
			(pts
				(xy -2.742184 -2.419096) (xy -3.415538 -2.643632) (xy -2.966466 -3.092704)
			)
			(stroke
				(width 0)
				(type default)
			)
			(fill yes)
			(layer "F.SilkS")
		)
		(fp_line
			(start -2.500122 -2.999994)
			(end 2.500122 -2.999994)
			(stroke
				(width 0.1)
				(type default)
			)
			(layer "F.Fab")
		)
		(fp_line
			(start -2.500122 2.999994)
			(end -2.500122 -2.999994)
			(stroke
				(width 0.1)
				(type default)
			)
			(layer "F.Fab")
		)
		(fp_line
			(start 2.500122 -2.999994)
			(end 2.500122 2.999994)
			(stroke
				(width 0.1)
				(type default)
			)
			(layer "F.Fab")
		)
		(fp_line
			(start 2.500122 2.999994)
			(end -2.500122 2.999994)
			(stroke
				(width 0.1)
				(type default)
			)
			(layer "F.Fab")
		)
		(fp_poly
			(pts
				(xy -4.218432 -2.783078) (xy -4.218432 -1.767078) (xy -3.202432 -2.275078)
			)
			(stroke
				(width 0)
				(type default)
			)
			(fill yes)
			(layer "F.Fab")
		)
		(pad "1" smd rect
			(at -2.400046 -2.275078 90)
			(size 0.2286 0.6096)
			(layers "F.Cu" "F.Mask" "F.Paste")
			(net "PVDDCR_CPU1_P1_VOS5")
		)
		(pad "2" smd rect
			(at -2.400046 -1.82499 90)
			(size 0.2286 0.6096)
			(layers "F.Cu" "F.Mask" "F.Paste")
			(net "GND")
		)
		(pad "3" smd rect
			(at -2.400046 -1.374902 90)
			(size 0.2286 0.6096)
			(layers "F.Cu" "F.Mask" "F.Paste")
			(net "PVDDCR_CPU1_P1_VCC5")
		)
		(pad "4" smd rect
			(at -2.400046 -0.925068 90)
			(size 0.2286 0.6096)
			(layers "F.Cu" "F.Mask" "F.Paste")
			(net "PVDDCR_CPU1_P1_PVCC")
		)
		(pad "5" smd rect
			(at -2.400046 -0.47498 90)
			(size 0.2286 0.6096)
			(layers "F.Cu" "F.Mask" "F.Paste")
			(net "GND")
		)
		(pad "6" smd rect
			(at -2.400046 -0.024892 90)
			(size 0.2286 0.6096)
			(layers "F.Cu" "F.Mask" "F.Paste")
			(net "NC_PVDDCR_CPU1_P1_GL1_5")
		)
		(pad "7_9-20_24" smd circle
			(at 0 1.150112 90)
			(size 0 0)
			(layers "F.Cu" "F.Mask" "F.Paste")
			(net "GND")
		)
		(pad "10_19" smd rect
			(at 0 2.899918 90)
			(size 0.6096 4.318)
			(layers "F.Cu" "F.Mask" "F.Paste")
			(net "SW_PVDDCR_CPU1_P1_SW5")
		)
		(pad "25_29" smd rect
			(at 1.549908 -1.279906 270)
			(size 2.0574 2.3114)
			(layers "F.Cu" "F.Mask" "F.Paste")
			(net "SW_P12V_AUX_PVDDCR_CPU1_P1_FLT")
		)
		(pad "30" smd rect
			(at 2.05994 -2.899918)
			(size 0.2286 0.6096)
			(layers "F.Cu" "F.Mask" "F.Paste")
			(net "SW_P12V_AUX_PVDDCR_CPU1_P1_FLT")
		)
		(pad "31" smd rect
			(at 1.610106 -2.899918)
			(size 0.2286 0.6096)
			(layers "F.Cu" "F.Mask" "F.Paste")
			(net "NC_PVDDCR_CPU1_P1_DNC5")
		)
		(pad "32" smd rect
			(at 1.160018 -2.899918)
			(size 0.2286 0.6096)
			(layers "F.Cu" "F.Mask" "F.Paste")
			(net "SW_PVDDCR_CPU1_P1_BOOTR5")
		)
		(pad "33" smd rect
			(at 0.70993 -2.899918)
			(size 0.2286 0.6096)
			(layers "F.Cu" "F.Mask" "F.Paste")
			(net "SW_PVDDCR_CPU1_P1_BOOT5")
		)
		(pad "34" smd rect
			(at 0.260096 -2.899918)
			(size 0.2286 0.6096)
			(layers "F.Cu" "F.Mask" "F.Paste")
			(net "PVDDCR_CPU1_P1_PWM5")
		)
		(pad "35" smd rect
			(at -0.189992 -2.899918)
			(size 0.2286 0.6096)
			(layers "F.Cu" "F.Mask" "F.Paste")
			(net "PVDDCR_CPU1_P1_VCC5")
		)
		(pad "36" smd rect
			(at -0.64008 -2.899918)
			(size 0.2286 0.6096)
			(layers "F.Cu" "F.Mask" "F.Paste")
			(net "PVDDCR_CPU1_P1_TEMP0")
		)
		(pad "37" smd rect
			(at -1.089914 -2.899918)
			(size 0.2286 0.6096)
			(layers "F.Cu" "F.Mask" "F.Paste")
			(net "PVDDCR_CPU1_P1_LSET5")
		)
		(pad "38" smd rect
			(at -1.540002 -2.899918)
			(size 0.2286 0.6096)
			(layers "F.Cu" "F.Mask" "F.Paste")
			(net "PVDDCR_CPU1_P1_IMON5")
		)
		(pad "39" smd rect
			(at -1.99009 -2.899918)
			(size 0.2286 0.6096)
			(layers "F.Cu" "F.Mask" "F.Paste")
			(net "PVDDCR_CPU1_P1_VCCS")
		)
		(pad "40" smd rect
			(at -0.87503 -1.27508)
			(size 1.7526 1.9558)
			(layers "F.Cu" "F.Mask" "F.Paste")
			(net "GND")
		)
		(pad "41" smd rect
			(at -1.525016 0.249936 270)
			(size 0.3048 0.4572)
			(layers "F.Cu" "F.Mask" "F.Paste")
			(net "NC_PVDDCR_CPU1_P1_GL2_5")
		)
		(zone
			(layer "F.Cu")
			(hatch none 0.5)
			(connect_pads
				(clearance 0)
			)
			(min_thickness 0.25)
			(keepout
				(tracks not_allowed)
				(vias allowed)
				(pads allowed)
				(copperpour not_allowed)
				(footprints allowed)
			)
			(placement
				(enabled no)
				(sheetname "")
			)
			(fill
				(thermal_gap 0.5)
				(thermal_bridge_width 0.5)
				(island_removal_mode 0)
			)
			(polygon
				(pts
					(xy 92.953332 -332.450694) (xy 92.953332 -332.778608) (xy 97.953576 -332.778608) (xy 97.953576 -332.455774)
					(xy 97.663254 -332.455774) (xy 97.663254 -332.484984) (xy 93.243654 -332.484984) (xy 93.243654 -332.450694)
				)
			)
		)
		(zone
			(layer "F.Cu")
			(hatch none 0.5)
			(connect_pads
				(clearance 0)
			)
			(min_thickness 0.25)
			(keepout
				(tracks not_allowed)
				(vias allowed)
				(pads allowed)
				(copperpour not_allowed)
				(footprints allowed)
			)
			(placement
				(enabled no)
				(sheetname "")
			)
			(fill
				(thermal_gap 0.5)
				(thermal_bridge_width 0.5)
				(island_removal_mode 0)
			)
			(polygon
				(pts
					(xy 95.505524 -335.275682) (xy 95.505524 -337.333082) (xy 93.651324 -337.333082) (xy 93.651324 -337.092036)
					(xy 93.409008 -337.092036) (xy 93.409008 -337.57362) (xy 97.152714 -337.57362) (xy 97.152714 -337.388708)
					(xy 95.796862 -337.388708) (xy 95.796862 -335.229708) (xy 97.953576 -335.229708) (xy 97.953576 -334.980026)
					(xy 95.80118 -334.980026)
				)
			)
		)
	)
	(footprint ""
		(layer "F.Cu")
		(at 94.4626 -416.4076 180)
		(property "Reference" "R1373"
			(at 0 0 180)
			(layer "F.SilkS")
			(hide yes)
			(effects
				(font
					(size 1.27 1.27)
				)
			)
		)
		(property "Value" ""
			(at 0 0 180)
			(layer "F.Fab")
			(effects
				(font
					(size 1.27 1.27)
				)
			)
		)
		(duplicate_pad_numbers_are_jumpers no)
		(fp_line
			(start 0.32512 0.175006)
			(end -0.32512 0.175006)
			(stroke
				(width 0.1)
				(type default)
			)
			(layer "F.Fab")
		)
		(fp_line
			(start 0.32512 -0.175006)
			(end 0.32512 0.175006)
			(stroke
				(width 0.1)
				(type default)
			)
			(layer "F.Fab")
		)
		(fp_line
			(start -0.32512 0.175006)
			(end -0.32512 -0.175006)
			(stroke
				(width 0.1)
				(type default)
			)
			(layer "F.Fab")
		)
		(fp_line
			(start -0.32512 -0.175006)
			(end 0.32512 -0.175006)
			(stroke
				(width 0.1)
				(type default)
			)
			(layer "F.Fab")
		)
		(pad "1" smd rect
			(at -0.2667 0 180)
			(size 0.3048 0.381)
			(layers "F.Cu" "F.Mask" "F.Paste")
			(net "JTAG_TCK_RT_CPU1_P1")
		)
		(pad "2" smd rect
			(at 0.2667 0)
			(size 0.3048 0.381)
			(layers "F.Cu" "F.Mask" "F.Paste")
			(net "GND")
		)
	)
	(footprint ""
		(layer "F.Cu")
		(at 314.567316 -108.52277 180)
		(property "Reference" "R125"
			(at 0 0 180)
			(layer "F.SilkS")
			(hide yes)
			(effects
				(font
					(size 1.27 1.27)
				)
			)
		)
		(property "Value" ""
			(at 0 0 180)
			(layer "F.Fab")
			(effects
				(font
					(size 1.27 1.27)
				)
			)
		)
		(duplicate_pad_numbers_are_jumpers no)
		(fp_line
			(start 0.7874 0.4064)
			(end -0.7874 0.4064)
			(stroke
				(width 0.1524)
				(type default)
			)
			(layer "F.SilkS")
		)
		(fp_line
			(start 0.7874 -0.4064)
			(end 0.7874 0.4064)
			(stroke
				(width 0.1524)
				(type default)
			)
			(layer "F.SilkS")
		)
		(fp_line
			(start -0.7874 0.4064)
			(end -0.7874 -0.4064)
			(stroke
				(width 0.1524)
				(type default)
			)
			(layer "F.SilkS")
		)
		(fp_line
			(start -0.7874 -0.4064)
			(end 0.7874 -0.4064)
			(stroke
				(width 0.1524)
				(type default)
			)
			(layer "F.SilkS")
		)
		(fp_line
			(start 0.67945 0.3048)
			(end 0.120396 0.3048)
			(stroke
				(width 0.1)
				(type default)
			)
			(layer "F.Fab")
		)
		(fp_line
			(start 0.67945 -0.3048)
			(end 0.67945 0.3048)
			(stroke
				(width 0.1)
				(type default)
			)
			(layer "F.Fab")
		)
		(fp_line
			(start 0.12065 -0.2794)
			(end 0.12065 -0.3048)
			(stroke
				(width 0.1)
				(type default)
			)
			(layer "F.Fab")
		)
		(fp_line
			(start 0.12065 -0.3048)
			(end 0.67945 -0.3048)
			(stroke
				(width 0.1)
				(type default)
			)
			(layer "F.Fab")
		)
		(fp_line
			(start 0.120396 0.3048)
			(end 0.120396 0.2794)
			(stroke
				(width 0.1)
				(type default)
			)
			(layer "F.Fab")
		)
		(fp_line
			(start 0.120396 0.2794)
			(end -0.12065 0.2794)
			(stroke
				(width 0.1)
				(type default)
			)
			(layer "F.Fab")
		)
		(fp_line
			(start -0.12065 0.3048)
			(end -0.67945 0.3048)
			(stroke
				(width 0.1)
				(type default)
			)
			(layer "F.Fab")
		)
		(fp_line
			(start -0.12065 0.2794)
			(end -0.12065 0.3048)
			(stroke
				(width 0.1)
				(type default)
			)
			(layer "F.Fab")
		)
		(fp_line
			(start -0.12065 -0.2794)
			(end 0.12065 -0.2794)
			(stroke
				(width 0.1)
				(type default)
			)
			(layer "F.Fab")
		)
		(fp_line
			(start -0.12065 -0.305054)
			(end -0.12065 -0.2794)
			(stroke
				(width 0.1)
				(type default)
			)
			(layer "F.Fab")
		)
		(fp_line
			(start -0.67945 0.3048)
			(end -0.67945 -0.305054)
			(stroke
				(width 0.1)
				(type default)
			)
			(layer "F.Fab")
		)
		(fp_line
			(start -0.67945 -0.305054)
			(end -0.12065 -0.305054)
			(stroke
				(width 0.1)
				(type default)
			)
			(layer "F.Fab")
		)
		(pad "1" smd circle
			(at -0.40005 0 180)
			(size 0 0)
			(layers "F.Cu" "F.Mask" "F.Paste")
			(net "SMB_FRU_3V3AUX_SDA")
		)
		(pad "2" smd circle
			(at 0.40005 0 180)
			(size 0 0)
			(layers "F.Cu" "F.Mask" "F.Paste")
			(net "SMB_CPU_FRU_3V3AUX_SDA")
		)
	)
	(footprint ""
		(layer "F.Cu")
		(at 74.422 -56.134 -90)
		(property "Reference" "C1064"
			(at 0 0 270)
			(layer "F.SilkS")
			(hide yes)
			(effects
				(font
					(size 1.27 1.27)
				)
			)
		)
		(property "Value" ""
			(at 0 0 270)
			(layer "F.Fab")
			(effects
				(font
					(size 1.27 1.27)
				)
			)
		)
		(duplicate_pad_numbers_are_jumpers no)
		(fp_line
			(start -0.7874 0.4064)
			(end -0.7874 -0.4064)
			(stroke
				(width 0.1524)
				(type default)
			)
			(layer "F.SilkS")
		)
		(fp_line
			(start 0.7874 0.4064)
			(end -0.7874 0.4064)
			(stroke
				(width 0.1524)
				(type default)
			)
			(layer "F.SilkS")
		)
		(fp_line
			(start -0.7874 -0.4064)
			(end 0.7874 -0.4064)
			(stroke
				(width 0.1524)
				(type default)
			)
			(layer "F.SilkS")
		)
		(fp_line
			(start 0.7874 -0.4064)
			(end 0.7874 0.4064)
			(stroke
				(width 0.1524)
				(type default)
			)
			(layer "F.SilkS")
		)
		(fp_line
			(start -0.67945 0.3048)
			(end -0.67945 -0.305054)
			(stroke
				(width 0.1)
				(type default)
			)
			(layer "F.Fab")
		)
		(fp_line
			(start -0.12065 0.3048)
			(end -0.67945 0.3048)
			(stroke
				(width 0.1)
				(type default)
			)
			(layer "F.Fab")
		)
		(fp_line
			(start 0.120396 0.3048)
			(end 0.120396 0.2794)
			(stroke
				(width 0.1)
				(type default)
			)
			(layer "F.Fab")
		)
		(fp_line
			(start 0.67945 0.3048)
			(end 0.120396 0.3048)
			(stroke
				(width 0.1)
				(type default)
			)
			(layer "F.Fab")
		)
		(fp_line
			(start -0.12065 0.2794)
			(end -0.12065 0.3048)
			(stroke
				(width 0.1)
				(type default)
			)
			(layer "F.Fab")
		)
		(fp_line
			(start 0.120396 0.2794)
			(end -0.12065 0.2794)
			(stroke
				(width 0.1)
				(type default)
			)
			(layer "F.Fab")
		)
		(fp_line
			(start -0.12065 -0.2794)
			(end 0.12065 -0.2794)
			(stroke
				(width 0.1)
				(type default)
			)
			(layer "F.Fab")
		)
		(fp_line
			(start 0.12065 -0.2794)
			(end 0.12065 -0.3048)
			(stroke
				(width 0.1)
				(type default)
			)
			(layer "F.Fab")
		)
		(fp_line
			(start 0.12065 -0.3048)
			(end 0.67945 -0.3048)
			(stroke
				(width 0.1)
				(type default)
			)
			(layer "F.Fab")
		)
		(fp_line
			(start 0.67945 -0.3048)
			(end 0.67945 0.3048)
			(stroke
				(width 0.1)
				(type default)
			)
			(layer "F.Fab")
		)
		(fp_line
			(start -0.67945 -0.305054)
			(end -0.12065 -0.305054)
			(stroke
				(width 0.1)
				(type default)
			)
			(layer "F.Fab")
		)
		(fp_line
			(start -0.12065 -0.305054)
			(end -0.12065 -0.2794)
			(stroke
				(width 0.1)
				(type default)
			)
			(layer "F.Fab")
		)
		(pad "1" smd circle
			(at -0.40005 0 270)
			(size 0 0)
			(layers "F.Cu" "F.Mask" "F.Paste")
			(net "P3V3_AUX")
		)
		(pad "2" smd circle
			(at 0.40005 0 270)
			(size 0 0)
			(layers "F.Cu" "F.Mask" "F.Paste")
			(net "GND")
		)
	)
	(footprint ""
		(layer "F.Cu")
		(at 79.908908 -69.238114 90)
		(property "Reference" "R1169"
			(at 0 0 90)
			(layer "F.SilkS")
			(hide yes)
			(effects
				(font
					(size 1.27 1.27)
				)
			)
		)
		(property "Value" ""
			(at 0 0 90)
			(layer "F.Fab")
			(effects
				(font
					(size 1.27 1.27)
				)
			)
		)
		(duplicate_pad_numbers_are_jumpers no)
		(fp_line
			(start 0.7874 -0.4064)
			(end 0.7874 0.4064)
			(stroke
				(width 0.1524)
				(type default)
			)
			(layer "F.SilkS")
		)
		(fp_line
			(start -0.7874 -0.4064)
			(end 0.7874 -0.4064)
			(stroke
				(width 0.1524)
				(type default)
			)
			(layer "F.SilkS")
		)
		(fp_line
			(start 0.7874 0.4064)
			(end -0.7874 0.4064)
			(stroke
				(width 0.1524)
				(type default)
			)
			(layer "F.SilkS")
		)
		(fp_line
			(start -0.7874 0.4064)
			(end -0.7874 -0.4064)
			(stroke
				(width 0.1524)
				(type default)
			)
			(layer "F.SilkS")
		)
		(fp_line
			(start -0.12065 -0.305054)
			(end -0.12065 -0.2794)
			(stroke
				(width 0.1)
				(type default)
			)
			(layer "F.Fab")
		)
		(fp_line
			(start -0.67945 -0.305054)
			(end -0.12065 -0.305054)
			(stroke
				(width 0.1)
				(type default)
			)
			(layer "F.Fab")
		)
		(fp_line
			(start 0.67945 -0.3048)
			(end 0.67945 0.3048)
			(stroke
				(width 0.1)
				(type default)
			)
			(layer "F.Fab")
		)
		(fp_line
			(start 0.12065 -0.3048)
			(end 0.67945 -0.3048)
			(stroke
				(width 0.1)
				(type default)
			)
			(layer "F.Fab")
		)
		(fp_line
			(start 0.12065 -0.2794)
			(end 0.12065 -0.3048)
			(stroke
				(width 0.1)
				(type default)
			)
			(layer "F.Fab")
		)
		(fp_line
			(start -0.12065 -0.2794)
			(end 0.12065 -0.2794)
			(stroke
				(width 0.1)
				(type default)
			)
			(layer "F.Fab")
		)
		(fp_line
			(start 0.120396 0.2794)
			(end -0.12065 0.2794)
			(stroke
				(width 0.1)
				(type default)
			)
			(layer "F.Fab")
		)
		(fp_line
			(start -0.12065 0.2794)
			(end -0.12065 0.3048)
			(stroke
				(width 0.1)
				(type default)
			)
			(layer "F.Fab")
		)
		(fp_line
			(start 0.67945 0.3048)
			(end 0.120396 0.3048)
			(stroke
				(width 0.1)
				(type default)
			)
			(layer "F.Fab")
		)
		(fp_line
			(start 0.120396 0.3048)
			(end 0.120396 0.2794)
			(stroke
				(width 0.1)
				(type default)
			)
			(layer "F.Fab")
		)
		(fp_line
			(start -0.12065 0.3048)
			(end -0.67945 0.3048)
			(stroke
				(width 0.1)
				(type default)
			)
			(layer "F.Fab")
		)
		(fp_line
			(start -0.67945 0.3048)
			(end -0.67945 -0.305054)
			(stroke
				(width 0.1)
				(type default)
			)
			(layer "F.Fab")
		)
		(pad "1" smd circle
			(at -0.40005 0 90)
			(size 0 0)
			(layers "F.Cu" "F.Mask" "F.Paste")
			(net "OCP_V3_2_P3V3_PWRGD")
		)
		(pad "2" smd circle
			(at 0.40005 0 90)
			(size 0 0)
			(layers "F.Cu" "F.Mask" "F.Paste")
			(net "OCP_V3_2_P3V3_R2_PWRGD")
		)
	)
)
